# T6G (Grand Teton) — schematic netlist excerpt (pin names and nets, part order shuffled) for the footprints in the layout excerpt that follows; sources: Cadence DE-HDL packaged netlist, KiCad conversion of 04192023_DAF0TMB3IC0_F0TG_MB_C_brd_V02_OCP.brd

X9027  TP_TDR_4P_FTS  TP_TDR_4P_DIP EMPTY  pkg TH  page 261
  S1  = TDR_DIFF_85_NECK_IN5_DN
  P1  = T1_GND
  P2  = T1_GND
  S2  = TDR_DIFF_85_NECK_IN5_DP

R6115  Q_RES  2K 1% CHIP  pkg 0402LF  page 83 : A = RST_PERST_CPU1_SWB_N ; B = GND

(kicad_pcb
	(version 20260206)
	(generator "pcbnew")
	(generator_version "10.0")
	(general
		(thickness 1.6)
		(legacy_teardrops no)
	)
	(paper "A4")
	(title_block
		(title "04192023_DAF0TMB3IC0_F0TG_MB_C_brd_V02_OCP.brd")
		(comment 1 "Grand Teton / footprints 7332-7333 of 8354")
	)
	(layers
		(0 "F.Cu" signal "TOP")
		(4 "In1.Cu" signal "GND")
		(6 "In2.Cu" signal "IN1")
		(8 "In3.Cu" signal "GND1")
		(10 "In4.Cu" signal "IN2")
		(12 "In5.Cu" signal "GND2")
		(14 "In6.Cu" signal "IN3")
		(16 "In7.Cu" signal "GND3")
		(18 "In8.Cu" signal "VCC")
		(20 "In9.Cu" signal "VCC1")
		(22 "In10.Cu" signal "GND4")
		(24 "In11.Cu" signal "IN4")
		(26 "In12.Cu" signal "GND5")
		(28 "In13.Cu" signal "IN5")
		(30 "In14.Cu" signal "GND6")
		(32 "In15.Cu" signal "IN6")
		(34 "In16.Cu" signal "GND7")
		(2 "B.Cu" signal "BOTTOM")
		(9 "F.Adhes" user "F.Adhesive")
		(11 "B.Adhes" user "B.Adhesive")
		(13 "F.Paste" user "Package Geometry/Pastemask Top")
		(15 "B.Paste" user "Package Geometry/Pastemask Bottom")
		(5 "F.SilkS" user "Ref Des/Silkscreen Top")
		(7 "B.SilkS" user "Ref Des/Silkscreen Bottom")
		(1 "F.Mask" user "Board Geometry/Soldermask Top")
		(3 "B.Mask" user "Board Geometry/Soldermask Bottom")
		(17 "Dwgs.User" user "User.Drawings")
		(19 "Cmts.User" user "User.Comments")
		(21 "Eco1.User" user "User.Eco1")
		(23 "Eco2.User" user "User.Eco2")
		(25 "Edge.Cuts" user "Board Geometry/Outline")
		(27 "Margin" user)
		(31 "F.CrtYd" user "Package Geometry/Place Bound Top")
		(29 "B.CrtYd" user "Package Geometry/Place Bound Bottom")
		(35 "F.Fab" user "Ref Des/Assembly Top")
		(33 "B.Fab" user "Ref Des/Assembly Bottom")
	)
	(footprint ""
		(layer "B.Cu")
		(at 500.851424 -457.29398 -90)
		(property "Reference" "X9027"
			(at 4.7244 -1.61163 270)
			(unlocked yes)
			(layer "B.SilkS")
			(effects
				(font
					(size 0.7874 0.5842)
					(thickness 0.1524)
				)
				(justify left mirror)
			)
		)
		(property "Value" ""
			(at 0 0 90)
			(layer "B.Fab")
			(effects
				(font
					(size 1.27 1.27)
				)
				(justify mirror)
			)
		)
		(property "User Part Number" "N_A"
			(at -1.30175 1.27 180)
			(unlocked yes)
			(layer "Cmts.User")
			(hide yes)
			(effects
				(font
					(size 0.635 0.4064)
					(thickness 0.1524)
				)
				(justify mirror)
			)
		)
		(property "Device Type" "TP_TDR_4P_FTS_TH-TP_TDR_4P_DIP,EMPTY,TP15"
			(at -1.30175 1.27 180)
			(unlocked yes)
			(layer "B.Fab")
			(hide yes)
			(effects
				(font
					(size 0.635 0.4064)
					(thickness 0.1524)
				)
				(justify mirror)
			)
		)
		(duplicate_pad_numbers_are_jumpers no)
		(fp_line
			(start -2.54 3.81)
			(end -2.54 3.6703)
			(stroke
				(width 0.1524)
				(type default)
			)
			(layer "B.SilkS")
		)
		(fp_line
			(start 0 3.81)
			(end -2.54 3.81)
			(stroke
				(width 0.1524)
				(type default)
			)
			(layer "B.SilkS")
		)
		(fp_line
			(start 0 3.175)
			(end 0 3.81)
			(stroke
				(width 0.1524)
				(type default)
			)
			(layer "B.SilkS")
		)
		(fp_line
			(start -2.54 1.4097)
			(end -2.54 1.1303)
			(stroke
				(width 0.1524)
				(type default)
			)
			(layer "B.SilkS")
		)
		(fp_line
			(start 0 0.635)
			(end 0 1.905)
			(stroke
				(width 0.1524)
				(type default)
			)
			(layer "B.SilkS")
		)
		(fp_line
			(start -2.54 -1.1303)
			(end -2.54 -1.27)
			(stroke
				(width 0.1524)
				(type default)
			)
			(layer "B.SilkS")
		)
		(fp_line
			(start -2.54 -1.27)
			(end 0 -1.27)
			(stroke
				(width 0.1524)
				(type default)
			)
			(layer "B.SilkS")
		)
		(fp_line
			(start 0 -1.27)
			(end 0 -0.635)
			(stroke
				(width 0.1524)
				(type default)
			)
			(layer "B.SilkS")
		)
		(fp_poly
			(pts
				(xy 0.761746 0) (xy 2.285746 -0.762) (xy 2.285746 0.762)
			)
			(stroke
				(width 0)
				(type default)
			)
			(fill yes)
			(layer "B.SilkS")
		)
		(fp_line
			(start -2.54 3.81)
			(end -2.54 -1.27)
			(stroke
				(width 0.1)
				(type default)
			)
			(layer "B.Fab")
		)
		(fp_line
			(start 0 3.81)
			(end -2.54 3.81)
			(stroke
				(width 0.1)
				(type default)
			)
			(layer "B.Fab")
		)
		(fp_line
			(start -2.54 -1.27)
			(end 0 -1.27)
			(stroke
				(width 0.1)
				(type default)
			)
			(layer "B.Fab")
		)
		(fp_line
			(start 0 -1.27)
			(end 0 3.81)
			(stroke
				(width 0.1)
				(type default)
			)
			(layer "B.Fab")
		)
		(fp_poly
			(pts
				(xy 0.761746 0) (xy 2.285746 -0.762) (xy 2.285746 0.762)
			)
			(stroke
				(width 0)
				(type default)
			)
			(fill yes)
			(layer "B.Fab")
		)
		(pad "1" thru_hole circle
			(at 0 0 90)
			(size 1.0033 1.0033)
			(drill 0.249936)
			(layers "*.Cu" "*.Mask")
			(remove_unused_layers no)
			(net "TDR_DIFF_85_NECK_IN5_DN")
			(clearance 0.10795)
			(padstack
				(mode front_inner_back)
				(layer "Inner"
					(shape circle)
					(size 0.8001 0.8001)
					(clearance 0.1524)
				)
				(layer "B.Cu"
					(shape circle)
					(size 1.0033 1.0033)
					(thermal_gap 0.10795)
					(clearance 0.10795)
				)
			)
		)
		(pad "2" thru_hole circle
			(at -2.54 0 90)
			(size 1.9939 1.9939)
			(drill 0.249936)
			(layers "*.Cu" "*.Mask")
			(remove_unused_layers no)
			(net "T1_GND")
			(clearance 0.10795)
			(padstack
				(mode front_inner_back)
				(layer "Inner"
					(shape circle)
					(size 0.8001 0.8001)
					(clearance 0.1524)
				)
				(layer "B.Cu"
					(shape circle)
					(size 1.9939 1.9939)
					(thermal_gap 0.10795)
					(clearance 0.10795)
				)
			)
		)
		(pad "3" thru_hole circle
			(at -2.54 2.54 90)
			(size 1.9939 1.9939)
			(drill 0.249936)
			(layers "*.Cu" "*.Mask")
			(remove_unused_layers no)
			(net "T1_GND")
			(clearance 0.10795)
			(padstack
				(mode front_inner_back)
				(layer "Inner"
					(shape circle)
					(size 0.8001 0.8001)
					(clearance 0.1524)
				)
				(layer "B.Cu"
					(shape circle)
					(size 1.9939 1.9939)
					(thermal_gap 0.10795)
					(clearance 0.10795)
				)
			)
		)
		(pad "4" thru_hole circle
			(at 0 2.54 90)
			(size 1.0033 1.0033)
			(drill 0.249936)
			(layers "*.Cu" "*.Mask")
			(remove_unused_layers no)
			(net "TDR_DIFF_85_NECK_IN5_DP")
			(clearance 0.10795)
			(padstack
				(mode front_inner_back)
				(layer "Inner"
					(shape circle)
					(size 0.8001 0.8001)
					(clearance 0.1524)
				)
				(layer "B.Cu"
					(shape circle)
					(size 1.0033 1.0033)
					(thermal_gap 0.10795)
					(clearance 0.10795)
				)
			)
		)
	)
	(footprint ""
		(layer "B.Cu")
		(at 197.345808 -124.877576 180)
		(property "Reference" "R6115"
			(at 0 0 0)
			(layer "B.SilkS")
			(hide yes)
			(effects
				(font
					(size 1.27 1.27)
				)
				(justify mirror)
			)
		)
		(property "Value" ""
			(at 0 0 0)
			(layer "B.Fab")
			(effects
				(font
					(size 1.27 1.27)
				)
				(justify mirror)
			)
		)
		(duplicate_pad_numbers_are_jumpers no)
		(fp_line
			(start 0.7874 0.4064)
			(end 0.7874 -0.4064)
			(stroke
				(width 0.1524)
				(type default)
			)
			(layer "B.SilkS")
		)
		(fp_line
			(start 0.7874 -0.4064)
			(end -0.7874 -0.4064)
			(stroke
				(width 0.1524)
				(type default)
			)
			(layer "B.SilkS")
		)
		(fp_line
			(start -0.7874 0.4064)
			(end 0.7874 0.4064)
			(stroke
				(width 0.1524)
				(type default)
			)
			(layer "B.SilkS")
		)
		(fp_line
			(start -0.7874 -0.4064)
			(end -0.7874 0.4064)
			(stroke
				(width 0.1524)
				(type default)
			)
			(layer "B.SilkS")
		)
		(fp_line
			(start 0.67945 0.3048)
			(end 0.67945 -0.305054)
			(stroke
				(width 0.1)
				(type default)
			)
			(layer "B.Fab")
		)
		(fp_line
			(start 0.67945 -0.305054)
			(end 0.12065 -0.305054)
			(stroke
				(width 0.1)
				(type default)
			)
			(layer "B.Fab")
		)
		(fp_line
			(start 0.12065 0.3048)
			(end 0.67945 0.3048)
			(stroke
				(width 0.1)
				(type default)
			)
			(layer "B.Fab")
		)
		(fp_line
			(start 0.12065 0.2794)
			(end 0.12065 0.3048)
			(stroke
				(width 0.1)
				(type default)
			)
			(layer "B.Fab")
		)
		(fp_line
			(start 0.12065 -0.2794)
			(end -0.12065 -0.2794)
			(stroke
				(width 0.1)
				(type default)
			)
			(layer "B.Fab")
		)
		(fp_line
			(start 0.12065 -0.305054)
			(end 0.12065 -0.2794)
			(stroke
				(width 0.1)
				(type default)
			)
			(layer "B.Fab")
		)
		(fp_line
			(start -0.120396 0.3048)
			(end -0.120396 0.2794)
			(stroke
				(width 0.1)
				(type default)
			)
			(layer "B.Fab")
		)
		(fp_line
			(start -0.120396 0.2794)
			(end 0.12065 0.2794)
			(stroke
				(width 0.1)
				(type default)
			)
			(layer "B.Fab")
		)
		(fp_line
			(start -0.12065 -0.2794)
			(end -0.12065 -0.3048)
			(stroke
				(width 0.1)
				(type default)
			)
			(layer "B.Fab")
		)
		(fp_line
			(start -0.12065 -0.3048)
			(end -0.67945 -0.3048)
			(stroke
				(width 0.1)
				(type default)
			)
			(layer "B.Fab")
		)
		(fp_line
			(start -0.67945 0.3048)
			(end -0.120396 0.3048)
			(stroke
				(width 0.1)
				(type default)
			)
			(layer "B.Fab")
		)
		(fp_line
			(start -0.67945 -0.3048)
			(end -0.67945 0.3048)
			(stroke
				(width 0.1)
				(type default)
			)
			(layer "B.Fab")
		)
		(pad "1" smd circle
			(at 0.40005 0)
			(size 0 0)
			(layers "B.Cu" "B.Mask" "B.Paste")
			(net "RST_PERST_CPU1_SWB_N")
		)
		(pad "2" smd circle
			(at -0.40005 0)
			(size 0 0)
			(layers "B.Cu" "B.Mask" "B.Paste")
			(net "GND")
		)
	)
)
